(kicad_pcb
	(version 20260206)
	(generator "pcbnew")
	(generator_version "10.0")
	(general
		(thickness 1.6)
		(legacy_teardrops no)
	)
	(paper "A4")
	(title_block
		(title "01162023_DA0F0TEBIF0_F0T_Expander_BD_F_brd_V02_OCP.brd")
		(comment 1 "Grand Teton / footprints 1648-1654 of 9728")
	)
	(layers
		(0 "F.Cu" signal "TOP")
		(4 "In1.Cu" signal "GND")
		(6 "In2.Cu" signal "VCC")
		(8 "In3.Cu" signal "VCC1")
		(10 "In4.Cu" signal "GND1")
		(12 "In5.Cu" signal "IN1")
		(14 "In6.Cu" signal "GND2")
		(16 "In7.Cu" signal "IN2")
		(18 "In8.Cu" signal "GND3")
		(20 "In9.Cu" signal "IN3")
		(22 "In10.Cu" signal "GND4")
		(24 "In11.Cu" signal "IN4")
		(26 "In12.Cu" signal "GND5")
		(28 "In13.Cu" signal "IN5")
		(30 "In14.Cu" signal "GND6")
		(32 "In15.Cu" signal "IN6")
		(34 "In16.Cu" signal "GND7")
		(2 "B.Cu" signal "BOTTOM")
		(9 "F.Adhes" user "F.Adhesive")
		(11 "B.Adhes" user "B.Adhesive")
		(13 "F.Paste" user "Package Geometry/Pastemask Top")
		(15 "B.Paste" user "Package Geometry/Pastemask Bottom")
		(5 "F.SilkS" user "Ref Des/Silkscreen Top")
		(7 "B.SilkS" user "Ref Des/Silkscreen Bottom")
		(1 "F.Mask" user "Board Geometry/Soldermask Top")
		(3 "B.Mask" user "Board Geometry/Soldermask Bottom")
		(17 "Dwgs.User" user "User.Drawings")
		(19 "Cmts.User" user "User.Comments")
		(21 "Eco1.User" user "User.Eco1")
		(23 "Eco2.User" user "User.Eco2")
		(25 "Edge.Cuts" user "Board Geometry/Outline")
		(27 "Margin" user)
		(31 "F.CrtYd" user "Package Geometry/Place Bound Top")
		(29 "B.CrtYd" user "Package Geometry/Place Bound Bottom")
		(35 "F.Fab" user "Ref Des/Assembly Top")
		(33 "B.Fab" user "Ref Des/Assembly Bottom")
	)
	(footprint ""
		(layer "F.Cu")
		(at 255.701546 -207.1116 -90)
		(property "Reference" "R5067"
			(at 0 0 270)
			(layer "F.SilkS")
			(hide yes)
			(effects
				(font
					(size 1.27 1.27)
				)
			)
		)
		(property "Value" ""
			(at 0 0 270)
			(layer "F.Fab")
			(effects
				(font
					(size 1.27 1.27)
				)
			)
		)
		(duplicate_pad_numbers_are_jumpers no)
		(fp_line
			(start -0.7874 0.4064)
			(end -0.7874 -0.4064)
			(stroke
				(width 0.1524)
				(type default)
			)
			(layer "F.SilkS")
		)
		(fp_line
			(start 0.7874 0.4064)
			(end -0.7874 0.4064)
			(stroke
				(width 0.1524)
				(type default)
			)
			(layer "F.SilkS")
		)
		(fp_line
			(start -0.7874 -0.4064)
			(end 0.7874 -0.4064)
			(stroke
				(width 0.1524)
				(type default)
			)
			(layer "F.SilkS")
		)
		(fp_line
			(start 0.7874 -0.4064)
			(end 0.7874 0.4064)
			(stroke
				(width 0.1524)
				(type default)
			)
			(layer "F.SilkS")
		)
		(fp_line
			(start -0.67945 0.3048)
			(end -0.67945 -0.305054)
			(stroke
				(width 0.1)
				(type default)
			)
			(layer "F.Fab")
		)
		(fp_line
			(start -0.12065 0.3048)
			(end -0.67945 0.3048)
			(stroke
				(width 0.1)
				(type default)
			)
			(layer "F.Fab")
		)
		(fp_line
			(start 0.120396 0.3048)
			(end 0.120396 0.2794)
			(stroke
				(width 0.1)
				(type default)
			)
			(layer "F.Fab")
		)
		(fp_line
			(start 0.67945 0.3048)
			(end 0.120396 0.3048)
			(stroke
				(width 0.1)
				(type default)
			)
			(layer "F.Fab")
		)
		(fp_line
			(start -0.12065 0.2794)
			(end -0.12065 0.3048)
			(stroke
				(width 0.1)
				(type default)
			)
			(layer "F.Fab")
		)
		(fp_line
			(start 0.120396 0.2794)
			(end -0.12065 0.2794)
			(stroke
				(width 0.1)
				(type default)
			)
			(layer "F.Fab")
		)
		(fp_line
			(start -0.12065 -0.2794)
			(end 0.12065 -0.2794)
			(stroke
				(width 0.1)
				(type default)
			)
			(layer "F.Fab")
		)
		(fp_line
			(start 0.12065 -0.2794)
			(end 0.12065 -0.3048)
			(stroke
				(width 0.1)
				(type default)
			)
			(layer "F.Fab")
		)
		(fp_line
			(start 0.12065 -0.3048)
			(end 0.67945 -0.3048)
			(stroke
				(width 0.1)
				(type default)
			)
			(layer "F.Fab")
		)
		(fp_line
			(start 0.67945 -0.3048)
			(end 0.67945 0.3048)
			(stroke
				(width 0.1)
				(type default)
			)
			(layer "F.Fab")
		)
		(fp_line
			(start -0.67945 -0.305054)
			(end -0.12065 -0.305054)
			(stroke
				(width 0.1)
				(type default)
			)
			(layer "F.Fab")
		)
		(fp_line
			(start -0.12065 -0.305054)
			(end -0.12065 -0.2794)
			(stroke
				(width 0.1)
				(type default)
			)
			(layer "F.Fab")
		)
		(pad "1" smd circle
			(at -0.40005 0 270)
			(size 0 0)
			(layers "F.Cu" "F.Mask" "F.Paste")
			(net "P3V3_AUX")
		)
		(pad "2" smd circle
			(at 0.40005 0 270)
			(size 0 0)
			(layers "F.Cu" "F.Mask" "F.Paste")
			(net "JTAG_BIC_TDI_R")
		)
	)
	(footprint ""
		(layer "F.Cu")
		(at 379.015244 -59.546236 90)
		(property "Reference" "C2896"
			(at 0 0 90)
			(layer "F.SilkS")
			(hide yes)
			(effects
				(font
					(size 1.27 1.27)
				)
			)
		)
		(property "Value" ""
			(at 0 0 90)
			(layer "F.Fab")
			(effects
				(font
					(size 1.27 1.27)
				)
			)
		)
		(duplicate_pad_numbers_are_jumpers no)
		(fp_line
			(start 0.7874 -0.4064)
			(end 0.7874 0.4064)
			(stroke
				(width 0.1524)
				(type default)
			)
			(layer "F.SilkS")
		)
		(fp_line
			(start -0.7874 -0.4064)
			(end 0.7874 -0.4064)
			(stroke
				(width 0.1524)
				(type default)
			)
			(layer "F.SilkS")
		)
		(fp_line
			(start 0.7874 0.4064)
			(end -0.7874 0.4064)
			(stroke
				(width 0.1524)
				(type default)
			)
			(layer "F.SilkS")
		)
		(fp_line
			(start -0.7874 0.4064)
			(end -0.7874 -0.4064)
			(stroke
				(width 0.1524)
				(type default)
			)
			(layer "F.SilkS")
		)
		(fp_line
			(start -0.12065 -0.305054)
			(end -0.12065 -0.2794)
			(stroke
				(width 0.1)
				(type default)
			)
			(layer "F.Fab")
		)
		(fp_line
			(start -0.67945 -0.305054)
			(end -0.12065 -0.305054)
			(stroke
				(width 0.1)
				(type default)
			)
			(layer "F.Fab")
		)
		(fp_line
			(start 0.67945 -0.3048)
			(end 0.67945 0.3048)
			(stroke
				(width 0.1)
				(type default)
			)
			(layer "F.Fab")
		)
		(fp_line
			(start 0.12065 -0.3048)
			(end 0.67945 -0.3048)
			(stroke
				(width 0.1)
				(type default)
			)
			(layer "F.Fab")
		)
		(fp_line
			(start 0.12065 -0.2794)
			(end 0.12065 -0.3048)
			(stroke
				(width 0.1)
				(type default)
			)
			(layer "F.Fab")
		)
		(fp_line
			(start -0.12065 -0.2794)
			(end 0.12065 -0.2794)
			(stroke
				(width 0.1)
				(type default)
			)
			(layer "F.Fab")
		)
		(fp_line
			(start 0.120396 0.2794)
			(end -0.12065 0.2794)
			(stroke
				(width 0.1)
				(type default)
			)
			(layer "F.Fab")
		)
		(fp_line
			(start -0.12065 0.2794)
			(end -0.12065 0.3048)
			(stroke
				(width 0.1)
				(type default)
			)
			(layer "F.Fab")
		)
		(fp_line
			(start 0.67945 0.3048)
			(end 0.120396 0.3048)
			(stroke
				(width 0.1)
				(type default)
			)
			(layer "F.Fab")
		)
		(fp_line
			(start 0.120396 0.3048)
			(end 0.120396 0.2794)
			(stroke
				(width 0.1)
				(type default)
			)
			(layer "F.Fab")
		)
		(fp_line
			(start -0.12065 0.3048)
			(end -0.67945 0.3048)
			(stroke
				(width 0.1)
				(type default)
			)
			(layer "F.Fab")
		)
		(fp_line
			(start -0.67945 0.3048)
			(end -0.67945 -0.305054)
			(stroke
				(width 0.1)
				(type default)
			)
			(layer "F.Fab")
		)
		(pad "1" smd circle
			(at -0.40005 0 90)
			(size 0 0)
			(layers "F.Cu" "F.Mask" "F.Paste")
			(net "SSD13_AUX_P3V3_EN_R")
		)
		(pad "2" smd circle
			(at 0.40005 0 90)
			(size 0 0)
			(layers "F.Cu" "F.Mask" "F.Paste")
			(net "GND")
		)
	)
	(footprint ""
		(layer "F.Cu")
		(at 326.012556 -196.234304)
		(property "Reference" "R4244"
			(at 0 0 0)
			(layer "F.SilkS")
			(hide yes)
			(effects
				(font
					(size 1.27 1.27)
				)
			)
		)
		(property "Value" ""
			(at 0 0 0)
			(layer "F.Fab")
			(effects
				(font
					(size 1.27 1.27)
				)
			)
		)
		(duplicate_pad_numbers_are_jumpers no)
		(fp_line
			(start -0.7874 -0.4064)
			(end 0.7874 -0.4064)
			(stroke
				(width 0.1524)
				(type default)
			)
			(layer "F.SilkS")
		)
		(fp_line
			(start -0.7874 0.4064)
			(end -0.7874 -0.4064)
			(stroke
				(width 0.1524)
				(type default)
			)
			(layer "F.SilkS")
		)
		(fp_line
			(start 0.7874 -0.4064)
			(end 0.7874 0.4064)
			(stroke
				(width 0.1524)
				(type default)
			)
			(layer "F.SilkS")
		)
		(fp_line
			(start 0.7874 0.4064)
			(end -0.7874 0.4064)
			(stroke
				(width 0.1524)
				(type default)
			)
			(layer "F.SilkS")
		)
		(fp_line
			(start -0.67945 -0.305054)
			(end -0.12065 -0.305054)
			(stroke
				(width 0.1)
				(type default)
			)
			(layer "F.Fab")
		)
		(fp_line
			(start -0.67945 0.3048)
			(end -0.67945 -0.305054)
			(stroke
				(width 0.1)
				(type default)
			)
			(layer "F.Fab")
		)
		(fp_line
			(start -0.12065 -0.305054)
			(end -0.12065 -0.2794)
			(stroke
				(width 0.1)
				(type default)
			)
			(layer "F.Fab")
		)
		(fp_line
			(start -0.12065 -0.2794)
			(end 0.12065 -0.2794)
			(stroke
				(width 0.1)
				(type default)
			)
			(layer "F.Fab")
		)
		(fp_line
			(start -0.12065 0.2794)
			(end -0.12065 0.3048)
			(stroke
				(width 0.1)
				(type default)
			)
			(layer "F.Fab")
		)
		(fp_line
			(start -0.12065 0.3048)
			(end -0.67945 0.3048)
			(stroke
				(width 0.1)
				(type default)
			)
			(layer "F.Fab")
		)
		(fp_line
			(start 0.120396 0.2794)
			(end -0.12065 0.2794)
			(stroke
				(width 0.1)
				(type default)
			)
			(layer "F.Fab")
		)
		(fp_line
			(start 0.120396 0.3048)
			(end 0.120396 0.2794)
			(stroke
				(width 0.1)
				(type default)
			)
			(layer "F.Fab")
		)
		(fp_line
			(start 0.12065 -0.3048)
			(end 0.67945 -0.3048)
			(stroke
				(width 0.1)
				(type default)
			)
			(layer "F.Fab")
		)
		(fp_line
			(start 0.12065 -0.2794)
			(end 0.12065 -0.3048)
			(stroke
				(width 0.1)
				(type default)
			)
			(layer "F.Fab")
		)
		(fp_line
			(start 0.67945 -0.3048)
			(end 0.67945 0.3048)
			(stroke
				(width 0.1)
				(type default)
			)
			(layer "F.Fab")
		)
		(fp_line
			(start 0.67945 0.3048)
			(end 0.120396 0.3048)
			(stroke
				(width 0.1)
				(type default)
			)
			(layer "F.Fab")
		)
		(pad "1" smd circle
			(at -0.40005 0)
			(size 0 0)
			(layers "F.Cu" "F.Mask" "F.Paste")
			(net "GND")
		)
		(pad "2" smd circle
			(at 0.40005 0)
			(size 0 0)
			(layers "F.Cu" "F.Mask" "F.Paste")
			(net "IOEXP_DBV2_A2")
		)
	)
	(footprint ""
		(layer "F.Cu")
		(at 295.877742 -113.251742)
		(property "Reference" "R290"
			(at 0 0 0)
			(layer "F.SilkS")
			(hide yes)
			(effects
				(font
					(size 1.27 1.27)
				)
			)
		)
		(property "Value" ""
			(at 0 0 0)
			(layer "F.Fab")
			(effects
				(font
					(size 1.27 1.27)
				)
			)
		)
		(duplicate_pad_numbers_are_jumpers no)
		(fp_line
			(start -0.7874 -0.4064)
			(end 0.7874 -0.4064)
			(stroke
				(width 0.1524)
				(type default)
			)
			(layer "F.SilkS")
		)
		(fp_line
			(start -0.7874 0.4064)
			(end -0.7874 -0.4064)
			(stroke
				(width 0.1524)
				(type default)
			)
			(layer "F.SilkS")
		)
		(fp_line
			(start 0.7874 -0.4064)
			(end 0.7874 0.4064)
			(stroke
				(width 0.1524)
				(type default)
			)
			(layer "F.SilkS")
		)
		(fp_line
			(start 0.7874 0.4064)
			(end -0.7874 0.4064)
			(stroke
				(width 0.1524)
				(type default)
			)
			(layer "F.SilkS")
		)
		(fp_line
			(start -0.67945 -0.305054)
			(end -0.12065 -0.305054)
			(stroke
				(width 0.1)
				(type default)
			)
			(layer "F.Fab")
		)
		(fp_line
			(start -0.67945 0.3048)
			(end -0.67945 -0.305054)
			(stroke
				(width 0.1)
				(type default)
			)
			(layer "F.Fab")
		)
		(fp_line
			(start -0.12065 -0.305054)
			(end -0.12065 -0.2794)
			(stroke
				(width 0.1)
				(type default)
			)
			(layer "F.Fab")
		)
		(fp_line
			(start -0.12065 -0.2794)
			(end 0.12065 -0.2794)
			(stroke
				(width 0.1)
				(type default)
			)
			(layer "F.Fab")
		)
		(fp_line
			(start -0.12065 0.2794)
			(end -0.12065 0.3048)
			(stroke
				(width 0.1)
				(type default)
			)
			(layer "F.Fab")
		)
		(fp_line
			(start -0.12065 0.3048)
			(end -0.67945 0.3048)
			(stroke
				(width 0.1)
				(type default)
			)
			(layer "F.Fab")
		)
		(fp_line
			(start 0.120396 0.2794)
			(end -0.12065 0.2794)
			(stroke
				(width 0.1)
				(type default)
			)
			(layer "F.Fab")
		)
		(fp_line
			(start 0.120396 0.3048)
			(end 0.120396 0.2794)
			(stroke
				(width 0.1)
				(type default)
			)
			(layer "F.Fab")
		)
		(fp_line
			(start 0.12065 -0.3048)
			(end 0.67945 -0.3048)
			(stroke
				(width 0.1)
				(type default)
			)
			(layer "F.Fab")
		)
		(fp_line
			(start 0.12065 -0.2794)
			(end 0.12065 -0.3048)
			(stroke
				(width 0.1)
				(type default)
			)
			(layer "F.Fab")
		)
		(fp_line
			(start 0.67945 -0.3048)
			(end 0.67945 0.3048)
			(stroke
				(width 0.1)
				(type default)
			)
			(layer "F.Fab")
		)
		(fp_line
			(start 0.67945 0.3048)
			(end 0.120396 0.3048)
			(stroke
				(width 0.1)
				(type default)
			)
			(layer "F.Fab")
		)
		(pad "1" smd circle
			(at -0.40005 0)
			(size 0 0)
			(layers "F.Cu" "F.Mask" "F.Paste")
			(net "RST_SMB_NIC5_MUX_ISO_N")
		)
		(pad "2" smd circle
			(at 0.40005 0)
			(size 0 0)
			(layers "F.Cu" "F.Mask" "F.Paste")
			(net "P3V3_NIC5")
		)
	)
	(footprint ""
		(layer "F.Cu")
		(at 22.416008 -350.098614 90)
		(property "Reference" "C2154"
			(at 0 0 90)
			(layer "F.SilkS")
			(hide yes)
			(effects
				(font
					(size 1.27 1.27)
				)
			)
		)
		(property "Value" ""
			(at 0 0 90)
			(layer "F.Fab")
			(effects
				(font
					(size 1.27 1.27)
				)
			)
		)
		(duplicate_pad_numbers_are_jumpers no)
		(fp_line
			(start 0.299974 -0.150114)
			(end 0.299974 0.150114)
			(stroke
				(width 0.1)
				(type default)
			)
			(layer "F.Fab")
		)
		(fp_line
			(start -0.299974 -0.150114)
			(end 0.299974 -0.150114)
			(stroke
				(width 0.1)
				(type default)
			)
			(layer "F.Fab")
		)
		(fp_line
			(start 0.299974 0.150114)
			(end -0.299974 0.150114)
			(stroke
				(width 0.1)
				(type default)
			)
			(layer "F.Fab")
		)
		(fp_line
			(start -0.299974 0.150114)
			(end -0.299974 -0.150114)
			(stroke
				(width 0.1)
				(type default)
			)
			(layer "F.Fab")
		)
		(pad "1" smd rect
			(at -0.2667 0 90)
			(size 0.3048 0.381)
			(layers "F.Cu" "F.Mask" "F.Paste")
			(net "P5E_PEX0_STN4_TX_DP<78>")
		)
		(pad "2" smd rect
			(at 0.2667 0 90)
			(size 0.3048 0.381)
			(layers "F.Cu" "F.Mask" "F.Paste")
			(net "P5E_PEX0_STN4_TX_C_DP<78>")
		)
	)
	(footprint ""
		(layer "F.Cu")
		(at 129.207006 -275.81606)
		(property "Reference" "PC6614"
			(at 0 0 0)
			(layer "F.SilkS")
			(hide yes)
			(effects
				(font
					(size 1.27 1.27)
				)
			)
		)
		(property "Value" ""
			(at 0 0 0)
			(layer "F.Fab")
			(effects
				(font
					(size 1.27 1.27)
				)
			)
		)
		(duplicate_pad_numbers_are_jumpers no)
		(fp_line
			(start -1.524 -0.762)
			(end 1.524 -0.762)
			(stroke
				(width 0.1524)
				(type default)
			)
			(layer "F.SilkS")
		)
		(fp_line
			(start -1.524 0.762)
			(end -1.524 -0.762)
			(stroke
				(width 0.1524)
				(type default)
			)
			(layer "F.SilkS")
		)
		(fp_line
			(start 1.524 -0.762)
			(end 1.524 0.762)
			(stroke
				(width 0.1524)
				(type default)
			)
			(layer "F.SilkS")
		)
		(fp_line
			(start 1.524 0.762)
			(end -1.524 0.762)
			(stroke
				(width 0.1524)
				(type default)
			)
			(layer "F.SilkS")
		)
		(fp_line
			(start -1.1049 -0.724916)
			(end -1.1049 0.724916)
			(stroke
				(width 0.1)
				(type default)
			)
			(layer "F.Fab")
		)
		(fp_line
			(start -1.1049 0.724916)
			(end 1.1049 0.724916)
			(stroke
				(width 0.1)
				(type default)
			)
			(layer "F.Fab")
		)
		(fp_line
			(start 1.1049 -0.724916)
			(end -1.1049 -0.724916)
			(stroke
				(width 0.1)
				(type default)
			)
			(layer "F.Fab")
		)
		(fp_line
			(start 1.1049 0.724916)
			(end 1.1049 -0.724916)
			(stroke
				(width 0.1)
				(type default)
			)
			(layer "F.Fab")
		)
		(pad "1" smd rect
			(at -0.889 0 180)
			(size 1.016 1.27)
			(layers "F.Cu" "F.Mask" "F.Paste")
			(net "SW_P12V_P0V8_PEX1_FLT")
		)
		(pad "2" smd rect
			(at 0.889 0 180)
			(size 1.016 1.27)
			(layers "F.Cu" "F.Mask" "F.Paste")
			(net "GND")
		)
	)
	(footprint ""
		(layer "F.Cu")
		(at 109.58195 -79.822294 90)
		(property "Reference" "R1140"
			(at 0 0 90)
			(layer "F.SilkS")
			(hide yes)
			(effects
				(font
					(size 1.27 1.27)
				)
			)
		)
		(property "Value" ""
			(at 0 0 90)
			(layer "F.Fab")
			(effects
				(font
					(size 1.27 1.27)
				)
			)
		)
		(duplicate_pad_numbers_are_jumpers no)
		(fp_line
			(start -0.7874 -0.4064)
			(end 0.7874 -0.4064)
			(stroke
				(width 0.1524)
				(type default)
			)
			(layer "F.SilkS")
		)
		(fp_line
			(start -0.12065 -0.305054)
			(end -0.12065 -0.2794)
			(stroke
				(width 0.1)
				(type default)
			)
			(layer "F.Fab")
		)
		(fp_line
			(start -0.67945 -0.305054)
			(end -0.12065 -0.305054)
			(stroke
				(width 0.1)
				(type default)
			)
			(layer "F.Fab")
		)
		(fp_line
			(start 0.67945 -0.3048)
			(end 0.67945 0.3048)
			(stroke
				(width 0.1)
				(type default)
			)
			(layer "F.Fab")
		)
		(fp_line
			(start 0.12065 -0.3048)
			(end 0.67945 -0.3048)
			(stroke
				(width 0.1)
				(type default)
			)
			(layer "F.Fab")
		)
		(fp_line
			(start 0.12065 -0.2794)
			(end 0.12065 -0.3048)
			(stroke
				(width 0.1)
				(type default)
			)
			(layer "F.Fab")
		)
		(fp_line
			(start -0.12065 -0.2794)
			(end 0.12065 -0.2794)
			(stroke
				(width 0.1)
				(type default)
			)
			(layer "F.Fab")
		)
		(fp_line
			(start 0.120396 0.2794)
			(end -0.12065 0.2794)
			(stroke
				(width 0.1)
				(type default)
			)
			(layer "F.Fab")
		)
		(fp_line
			(start -0.12065 0.2794)
			(end -0.12065 0.3048)
			(stroke
				(width 0.1)
				(type default)
			)
			(layer "F.Fab")
		)
		(fp_line
			(start 0.67945 0.3048)
			(end 0.120396 0.3048)
			(stroke
				(width 0.1)
				(type default)
			)
			(layer "F.Fab")
		)
		(fp_line
			(start 0.120396 0.3048)
			(end 0.120396 0.2794)
			(stroke
				(width 0.1)
				(type default)
			)
			(layer "F.Fab")
		)
		(fp_line
			(start -0.12065 0.3048)
			(end -0.67945 0.3048)
			(stroke
				(width 0.1)
				(type default)
			)
			(layer "F.Fab")
		)
		(fp_line
			(start -0.67945 0.3048)
			(end -0.67945 -0.305054)
			(stroke
				(width 0.1)
				(type default)
			)
			(layer "F.Fab")
		)
		(pad "1" smd circle
			(at -0.40005 0 90)
			(size 0 0)
			(layers "F.Cu" "F.Mask" "F.Paste")
			(net "CLK_100M_DB800ZL_SSD2_R_DP")
		)
		(pad "2" smd circle
			(at 0.40005 0 90)
			(size 0 0)
			(layers "F.Cu" "F.Mask" "F.Paste")
			(net "CLK_100M_DB800ZL_SSD2_DP")
		)
	)
)
